FILE_TYPE = CONNECTIVITY;
{Allegro Design Entry HDL 17.4-2019 S026 (4007227) 1/17/2022}
"PAGE_NUMBER" = 452;
0"NC";
1"GND\g";
2"GND\g";
3"P1V8_CPU1_RT_1D\g";
4"GND\g";
5"RT_CPU1_P2_VQPS";
6"P1V8_CPU1_RT2_1A_1D\g";
7"GND\g";
8"NCF_CPU1_P2_GND";
9"GND\g";
10"NCF_A1_CPU1_P2_GND";
11"P0V9_CPU1_RT2_2A\g";
12"P0V9_CPU1_RT_2D\g";
13"P0V9_CPU1_RT2_2A_2D\g";
14"P1V8_CPU1_RT2_1A\g";
%"P1V0"
"1","(-7525,5100)","0","pure_quanta_power","I10";
;
HDL_POWER"P1V8_CPU1_RT2_1A"
CDS_LIB"pure_quanta_power";
"A"14;
%"VCC_CORE"
"1","(-5000,4800)","0","pure_quanta_power","I11";
;
HDL_POWER"P0V9_CPU1_RT2_2A_2D"
CDS_LIB"pure_quanta_power";
"A"13;
%"VCC_CORE"
"1","(-4425,5275)","0","pure_quanta_power","I12";
;
HDL_POWER"P0V9_CPU1_RT2_2A"
CDS_LIB"pure_quanta_power";
"A"11;
%"UNIVERSAL_GND"
"1","(-2875,1575)","0","pure_quanta_power","I13";
;
CDS_LIB"pure_quanta_power"
HDL_POWER"GND";
"A"9;
%"UNIVERSAL_GND"
"1","(-1200,1200)","0","pure_quanta_power","I14";
;
CDS_LIB"pure_quanta_power"
HDL_POWER"GND";
"A"1;
%"Q_RES"
"2","(-1200,1500)","0","pure_quanta","I15";
;
LOCATION"R6797"
$SEC"1"
CDS_SEC"1"
MATERIAL"CHIP"
PACK_TYPE"0201LF"
TOLERANCE"5%"
WATTAGE"1/20W"
VALUE"0"
CDS_LIB"pure_quanta"
PART_NUMBER"CS00001JE10";
"A"
$PN"1"8;
"B"
$PN"2"1;
%"UNIVERSAL_GND"
"1","(-1050,1750)","0","pure_quanta_power","I16";
;
CDS_LIB"pure_quanta_power"
HDL_POWER"GND";
"A"2;
%"UNIVERSAL_GND"
"1","(-825,2300)","0","pure_quanta_power","I17";
;
CDS_LIB"pure_quanta_power"
HDL_POWER"GND";
"A"7;
%"Q_RES"
"2","(-1050,2050)","0","pure_quanta","I18";
;
LOCATION"R6796"
$SEC"1"
CDS_SEC"1"
PACK_TYPE"0201LF"
MATERIAL"CHIP"
WATTAGE"1/20W"
TOLERANCE"5%"
VALUE"0"
CDS_LIB"pure_quanta"
PART_NUMBER"CS00001JE10";
"A"
$PN"1"10;
"B"
$PN"2"2;
%"PT5161LRS"
"5","(-2175,3825)","0","pure_quanta","I19";
;
LOCATION"U6016"
$SEC"5"
CDS_SEC"5"
PART_TYPE"SMLF"
VALUE"PT5161LRS"
MATERIAL"IC"
NEEDS_NO_SIZE"TRUE"
CDS_LMAN_SYM_OUTLINE"-350,2150,300,-2150"
CDS_LIB"pure_quanta"
PART_NUMBER"AJ051610U03";
"GND151"
$PN"V35"7;
"GND150"
$PN"V1"7;
"GND149"
$PN"U34"7;
"GND148"
$PN"U2"7;
"GND147"
$PN"T4"7;
"GND146"
$PN"T32"7;
"GND145"
$PN"T22"7;
"GND144"
$PN"T13"7;
"GND143"
$PN"L35"7;
"GND142"
$PN"L1"7;
"GND141"
$PN"K34"7;
"GND140"
$PN"K2"7;
"GND139"
$PN"J4"7;
"GND138"
$PN"J22"7;
"GND137"
$PN"H31"7;
"GND136"
$PN"H19"7;
"GND135"
$PN"H16"7;
"GND134"
$PN"H12"7;
"GND133"
$PN"FJ19"7;
"GND132"
$PN"FJ12"7;
"GND131"
$PN"FF21"7;
"GND130"
$PN"FF14"7;
"GND129"
$PN"FD35"7;
"GND128"
$PN"FD1"7;
"GND127"
$PN"FC9"7;
"GND126"
$PN"FC6"7;
"GND125"
$PN"FC3"7;
"GND124"
$PN"FC28"7;
"GND123"
$PN"FC25"7;
"GND122"
$PN"FC23"7;
"GND121"
$PN"FC19"7;
"GND120"
$PN"FB34"7;
"GND119"
$PN"FB2"7;
"GND118"
$PN"FA32"7;
"GND117"
$PN"FA15"7;
"GND116"
$PN"ET35"7;
"GND115"
$PN"ET1"7;
"GND114"
$PN"ER34"7;
"GND113"
$PN"ER2"7;
"GND112"
$PN"EP4"7;
"GND111"
$PN"EP32"7;
"GND110"
$PN"EP22"7;
"GND109"
$PN"EP13"7;
"GND108"
$PN"EJ35"7;
"GND107"
$PN"EJ1"7;
"GND106"
$PN"EH34"7;
"GND105"
$PN"EH2"7;
"GND104"
$PN"EG4"7;
"GND103"
$PN"EG32"7;
"GND102"
$PN"EG22"7;
"GND101"
$PN"EG13"7;
"GND100"
$PN"EB35"7;
"GND99"
$PN"EB1"7;
"GND98"
$PN"EA34"7;
"GND97"
$PN"EA2"7;
"GND96"
$PN"E33"7;
"GND95"
$PN"E27"7;
"GND94"
$PN"E14"7;
"GND93"
$PN"DY4"7;
"GND92"
$PN"DY32"7;
"GND91"
$PN"DY22"7;
"GND90"
$PN"DY13"7;
"GND89"
$PN"DR35"7;
"GND88"
$PN"DR1"7;
"GND87"
$PN"DP34"7;
"GND86"
$PN"DP2"7;
"GND85"
$PN"DN4"7;
"GND84"
$PN"DN32"7;
"GND83"
$PN"DN22"7;
"NCF_GND12"
$PN"FH34"8;
"NCF_GND11"
$PN"FH2"8;
"NCF_GND10"
$PN"FG35"8;
"NCF_GND9"
$PN"FG1"8;
"NCF_GND8"
$PN"FE34"8;
"NCF_GND7"
$PN"FE2"8;
"NCF_GND6"
$PN"D35"8;
"NCF_GND5"
$PN"D1"8;
"NCF_GND4"
$PN"C34"8;
"NCF_GND3"
$PN"C2"8;
"NCF_GND2"
$PN"A35"8;
"NCF_GND1"
$PN"A1"10;
"GND82"
$PN"DN13"9;
"GND81"
$PN"DH35"9;
"GND80"
$PN"DH1"9;
"GND79"
$PN"DG34"9;
"GND78"
$PN"DG2"9;
"GND77"
$PN"DF4"9;
"GND76"
$PN"DF32"9;
"GND75"
$PN"DF22"9;
"GND74"
$PN"DF13"9;
"GND73"
$PN"DA35"9;
"GND72"
$PN"DA1"9;
"GND71"
$PN"CY34"9;
"GND70"
$PN"CY2"9;
"GND69"
$PN"CW4"9;
"GND68"
$PN"CW32"9;
"GND67"
$PN"CW22"9;
"GND66"
$PN"CW13"9;
"GND65"
$PN"CP35"9;
"GND64"
$PN"CP1"9;
"GND63"
$PN"CN34"9;
"GND62"
$PN"CN2"9;
"GND61"
$PN"CM4"9;
"GND60"
$PN"CM32"9;
"GND59"
$PN"CM22"9;
"GND58"
$PN"CM13"9;
"GND57"
$PN"CG35"9;
"GND56"
$PN"CG1"9;
"GND55"
$PN"CF34"9;
"GND54"
$PN"CF2"9;
"GND53"
$PN"CE4"9;
"GND52"
$PN"CE32"9;
"GND51"
$PN"CE22"9;
"GND50"
$PN"CE13"9;
"GND49"
$PN"BY35"9;
"GND48"
$PN"BY1"9;
"GND47"
$PN"BW34"9;
"GND46"
$PN"BW2"9;
"GND45"
$PN"BV4"9;
"GND44"
$PN"BV32"9;
"GND43"
$PN"BV22"9;
"GND42"
$PN"BV13"9;
"GND41"
$PN"BN35"9;
"GND40"
$PN"BN1"9;
"GND39"
$PN"BM34"9;
"GND38"
$PN"BM2"9;
"GND37"
$PN"BL4"9;
"GND36"
$PN"BL32"9;
"GND35"
$PN"BL22"9;
"GND34"
$PN"BL13"9;
"GND33"
$PN"BF35"9;
"GND32"
$PN"BF1"9;
"GND31"
$PN"BE34"9;
"GND30"
$PN"BE2"9;
"GND29"
$PN"BD4"9;
"GND28"
$PN"BD32"9;
"GND27"
$PN"BD22"9;
"GND26"
$PN"BD13"9;
"GND25"
$PN"B19"9;
"GND24"
$PN"AW35"9;
"GND23"
$PN"AW1"9;
"GND22"
$PN"AV34"9;
"GND21"
$PN"AV2"9;
"GND20"
$PN"AU4"9;
"GND19"
$PN"AU32"9;
"GND18"
$PN"AU22"9;
"GND17"
$PN"AU13"9;
"GND16"
$PN"AM35"9;
"GND15"
$PN"AM1"9;
"GND14"
$PN"AL34"9;
"GND13"
$PN"AL2"9;
"GND12"
$PN"AK4"9;
"GND11"
$PN"AK32"9;
"GND10"
$PN"AK22"9;
"GND9"
$PN"AK13"9;
"GND8"
$PN"AE35"9;
"GND7"
$PN"AE1"9;
"GND6"
$PN"AD34"9;
"GND5"
$PN"AD2"9;
"GND4"
$PN"AC4"9;
"GND3"
$PN"AC32"9;
"GND2"
$PN"AC22"9;
"GND1"
$PN"AC13"9;
%"Q_RES"
"2","(-7400,3600)","0","pure_quanta","I20";
;
LOCATION"R6795"
$SEC"1"
CDS_SEC"1"
PACK_TYPE"0201LF"
TOLERANCE"1%"
VALUE"200"
WATTAGE"1/20W"
MATERIAL"CHIP"
CDS_LIB"pure_quanta"
PART_NUMBER"CS12001FE12";
"A"
$PN"1"5;
"B"
$PN"2"4;
%"Q_RES"
"2","(-8425,4150)","0","pure_quanta","I21";
;
LOCATION"R6794"
$SEC"1"
CDS_SEC"1"
MATERIAL"EMPTY"
VALUE"1K"
TOLERANCE"1%"
WATTAGE"1/20W"
PACK_TYPE"0201LF"
CDS_LIB"pure_quanta"
PART_NUMBER"CS21001FE07";
"A"
$PN"1"3;
"B"
$PN"2"5;
%"P1V0"
"1","(-8425,4375)","0","pure_quanta_power","I4";
;
HDL_POWER"P1V8_CPU1_RT_1D"
CDS_LIB"pure_quanta_power";
"A"3;
%"UNIVERSAL_GND"
"1","(-7400,3350)","0","pure_quanta_power","I5";
;
CDS_LIB"pure_quanta_power"
HDL_POWER"GND";
"A"4;
%"PT5161LRS"
"4","(-6250,4400)","0","pure_quanta","I7";
;
LOCATION"U6016"
$SEC"4"
CDS_SEC"4"
PART_TYPE"SMLF"
VALUE"PT5161LRS"
MATERIAL"IC"
NEEDS_NO_SIZE"TRUE"
CDS_LMAN_SYM_OUTLINE"-450,750,400,-750"
CDS_LIB"pure_quanta"
PART_NUMBER"AJ051610U03";
"PWR_2A_20"
$PN"T20"11;
"PWR_2A_19"
$PN"T17"11;
"PWR_2A_18"
$PN"EP20"11;
"PWR_2A_17"
$PN"EP17"11;
"PWR_2A_16"
$PN"EG20"11;
"PWR_2A_15"
$PN"EG17"11;
"PWR_2A_14"
$PN"DY20"11;
"PWR_2A_13"
$PN"DY17"11;
"PWR_2A_12"
$PN"DN20"11;
"PWR_2A_11"
$PN"DN17"11;
"PWR_2A_10"
$PN"DF20"13;
"PWR_2A_9"
$PN"DF17"13;
"PWR_2A_8"
$PN"BD20"13;
"PWR_2A_7"
$PN"BD17"13;
"PWR_2A_6"
$PN"AU20"11;
"PWR_2A_5"
$PN"AU17"11;
"PWR_2A_4"
$PN"AK20"11;
"PWR_2A_3"
$PN"AK17"11;
"PWR_2A_2"
$PN"AC20"11;
"PWR_2A_1"
$PN"AC17"11;
"PWR_1D"
$PN"BV17"6;
"PWR_2D_4"
$PN"CW20"12;
"PWR_2D_3"
$PN"CW17"12;
"PWR_2D_2"
$PN"BL20"12;
"PWR_2D_1"
$PN"BL17"12;
"PWR_1A_5"
$PN"CM20"14;
"PWR_1A_4"
$PN"CM17"14;
"PWR_1A_3"
$PN"CE20"14;
"PWR_1A_2"
$PN"CE17"14;
"PWR_1A_1"
$PN"BV20"14;
"VQPS"
$PN"G1"5;
%"P1V0"
"1","(-4400,4050)","0","pure_quanta_power","I8";
;
HDL_POWER"P0V9_CPU1_RT_2D"
CDS_LIB"pure_quanta_power";
"A"12;
%"P1V0"
"1","(-8100,4650)","0","pure_quanta_power","I9";
;
HDL_POWER"P1V8_CPU1_RT2_1A_1D"
CDS_LIB"pure_quanta_power";
"A"6;
END.
